(kicad_pcb
	(version 20241229)
	(generator "pcbnew")
	(generator_version "9.0")
	(general
		(thickness 1.61)
		(legacy_teardrops no)
	)
	(paper "A3")
	(title_block
		(title "RDIMM DDR5 Tester")
		(date "2026-05-21")
		(rev "2.2.0")
		(company "Antmicro")
		(comment 9 "footprints 27-31 of 796")
	)
	(layers
		(0 "F.Cu" signal)
		(4 "In1.Cu" power)
		(6 "In2.Cu" mixed)
		(8 "In3.Cu" power)
		(10 "In4.Cu" mixed)
		(12 "In5.Cu" power)
		(14 "In6.Cu" mixed)
		(16 "In7.Cu" power)
		(18 "In8.Cu" power)
		(20 "In9.Cu" mixed)
		(22 "In10.Cu" power)
		(2 "B.Cu" signal)
		(9 "F.Adhes" user "F.Adhesive")
		(11 "B.Adhes" user "B.Adhesive")
		(13 "F.Paste" user)
		(15 "B.Paste" user)
		(5 "F.SilkS" user "F.Silkscreen")
		(7 "B.SilkS" user "B.Silkscreen")
		(1 "F.Mask" user)
		(3 "B.Mask" user)
		(17 "Dwgs.User" user "User.Drawings")
		(19 "Cmts.User" user "User.Comments")
		(21 "Eco1.User" user "User.Eco1")
		(23 "Eco2.User" user "User.Eco2")
		(25 "Edge.Cuts" user)
		(27 "Margin" user)
		(31 "F.CrtYd" user "F.Courtyard")
		(29 "B.CrtYd" user "B.Courtyard")
		(35 "F.Fab" user)
		(33 "B.Fab" user)
	)
	(footprint "antmicro-footprints:C_0402_1005Metric"
		(layer "F.Cu")
		(at 141.525 144.907851 90)
		(descr "Capacitor SMD 0402")
		(tags "capacitor SMD 0402")
		(property "Reference" "C159"
			(at -5.992149 0.375 90)
			(layer "F.SilkS")
			(effects
				(font
					(size 0.7 0.7)
					(thickness 0.15)
				)
				(justify left bottom)
			)
		)
		(property "Value" "C_4u7_0402"
			(at -1.022927 2.155213 90)
			(layer "F.Fab")
			(effects
				(font
					(size 0.7 0.7)
					(thickness 0.15)
				)
				(justify left bottom)
			)
		)
		(property "Datasheet" "https://www.murata.com/products/productdetail?partno=GRM155R61A475MEAA%23"
			(at 0 0 90)
			(layer "F.Fab")
			(hide yes)
			(effects
				(font
					(size 1.27 1.27)
					(thickness 0.15)
				)
			)
		)
		(property "Manufacturer" "Murata"
			(at 0 0 90)
			(unlocked yes)
			(layer "F.Fab")
			(hide yes)
			(effects
				(font
					(size 1 1)
					(thickness 0.15)
				)
			)
		)
		(property "MPN" "GRM155R61A475MEAAD"
			(at 0 0 90)
			(unlocked yes)
			(layer "F.Fab")
			(hide yes)
			(effects
				(font
					(size 1 1)
					(thickness 0.15)
				)
			)
		)
		(property "Val" "4u7"
			(at 0 0 90)
			(unlocked yes)
			(layer "F.Fab")
			(hide yes)
			(effects
				(font
					(size 1 1)
					(thickness 0.15)
				)
			)
		)
		(property "License" "Apache-2.0"
			(at 0 0 90)
			(unlocked yes)
			(layer "F.Fab")
			(hide yes)
			(effects
				(font
					(size 1 1)
					(thickness 0.15)
				)
			)
		)
		(property "Author" "Antmicro"
			(at 0 0 90)
			(unlocked yes)
			(layer "F.Fab")
			(hide yes)
			(effects
				(font
					(size 1 1)
					(thickness 0.15)
				)
			)
		)
		(property "Voltage" ""
			(at 0 0 90)
			(unlocked yes)
			(layer "F.Fab")
			(hide yes)
			(effects
				(font
					(size 1 1)
					(thickness 0.15)
				)
			)
		)
		(property "Dielectric" ""
			(at 0 0 90)
			(unlocked yes)
			(layer "F.Fab")
			(hide yes)
			(effects
				(font
					(size 1 1)
					(thickness 0.15)
				)
			)
		)
		(sheetname "/Ethernet/")
		(sheetfile "ethernet.kicad_sch")
		(attr smd)
		(fp_rect
			(start -0.925 -0.47)
			(end 0.925 0.47)
			(stroke
				(width 0.05)
				(type default)
			)
			(fill no)
			(layer "F.CrtYd")
		)
		(fp_line
			(start 0.504 -0.25)
			(end 0.504 0.248)
			(stroke
				(width 0.15)
				(type solid)
			)
			(layer "F.Fab")
		)
		(fp_line
			(start -0.494 -0.25)
			(end 0.504 -0.25)
			(stroke
				(width 0.15)
				(type solid)
			)
			(layer "F.Fab")
		)
		(fp_line
			(start 0.504 0.248)
			(end -0.494 0.248)
			(stroke
				(width 0.15)
				(type solid)
			)
			(layer "F.Fab")
		)
		(fp_line
			(start -0.494 0.248)
			(end -0.494 -0.25)
			(stroke
				(width 0.15)
				(type solid)
			)
			(layer "F.Fab")
		)
		(fp_text user "Author: Antmicro"
			(at -0.939 3.399 90)
			(layer "F.Fab")
			(effects
				(font
					(size 0.7 0.7)
					(thickness 0.15)
				)
				(justify left bottom)
			)
		)
		(fp_text user "License: Apache-2.0"
			(at -0.939 5.799 90)
			(layer "F.Fab")
			(effects
				(font
					(size 0.7 0.7)
					(thickness 0.15)
				)
				(justify left bottom)
			)
		)
		(fp_text user "${REFERENCE}"
			(at -0.939 4.599 90)
			(layer "F.Fab")
			(effects
				(font
					(size 0.7 0.7)
					(thickness 0.15)
				)
				(justify left bottom)
			)
		)
		(pad "1" smd roundrect
			(at -0.48 0 90)
			(size 0.59 0.64)
			(layers "F.Cu" "F.Mask" "F.Paste")
			(roundrect_rratio 0.25)
			(net 1 "GND")
			(pintype "passive")
		)
		(pad "2" smd roundrect
			(at 0.48 0 90)
			(size 0.59 0.64)
			(layers "F.Cu" "F.Mask" "F.Paste")
			(roundrect_rratio 0.25)
			(net 96 "/Ethernet/AVDDL_PLL")
			(pintype "passive")
		)
	)
	(footprint "antmicro-footprints:C_0402_1005Metric"
		(layer "F.Cu")
		(at 129.625 142.507851 -90)
		(descr "Capacitor SMD 0402")
		(tags "capacitor SMD 0402")
		(property "Reference" "C138"
			(at -0.982851 1.6 90)
			(layer "F.SilkS")
			(effects
				(font
					(size 0.7 0.7)
					(thickness 0.15)
				)
				(justify right bottom)
			)
		)
		(property "Value" "C_470n_0402"
			(at -1.022927 2.155213 90)
			(layer "F.Fab")
			(effects
				(font
					(size 0.7 0.7)
					(thickness 0.15)
				)
				(justify right bottom)
			)
		)
		(property "Datasheet" "https://product.tdk.com/en/search/capacitor/ceramic/mlcc/info?part_no=C1005X5R1E474M050BB"
			(at 0 0 270)
			(layer "F.Fab")
			(hide yes)
			(effects
				(font
					(size 1.27 1.27)
					(thickness 0.15)
				)
			)
		)
		(property "Manufacturer" "TDK"
			(at 0 0 270)
			(unlocked yes)
			(layer "F.Fab")
			(hide yes)
			(effects
				(font
					(size 1 1)
					(thickness 0.15)
				)
			)
		)
		(property "MPN" "C1005X5R1E474M050BB"
			(at 0 0 270)
			(unlocked yes)
			(layer "F.Fab")
			(hide yes)
			(effects
				(font
					(size 1 1)
					(thickness 0.15)
				)
			)
		)
		(property "Val" "470n"
			(at 0 0 270)
			(unlocked yes)
			(layer "F.Fab")
			(hide yes)
			(effects
				(font
					(size 1 1)
					(thickness 0.15)
				)
			)
		)
		(property "License" "Apache-2.0"
			(at 0 0 270)
			(unlocked yes)
			(layer "F.Fab")
			(hide yes)
			(effects
				(font
					(size 1 1)
					(thickness 0.15)
				)
			)
		)
		(property "Author" "Antmicro"
			(at 0 0 270)
			(unlocked yes)
			(layer "F.Fab")
			(hide yes)
			(effects
				(font
					(size 1 1)
					(thickness 0.15)
				)
			)
		)
		(property "Voltage" ""
			(at 0 0 270)
			(unlocked yes)
			(layer "F.Fab")
			(hide yes)
			(effects
				(font
					(size 1 1)
					(thickness 0.15)
				)
			)
		)
		(property "Dielectric" ""
			(at 0 0 270)
			(unlocked yes)
			(layer "F.Fab")
			(hide yes)
			(effects
				(font
					(size 1 1)
					(thickness 0.15)
				)
			)
		)
		(sheetname "/Ethernet/")
		(sheetfile "ethernet.kicad_sch")
		(attr smd)
		(fp_rect
			(start -0.925 -0.47)
			(end 0.925 0.47)
			(stroke
				(width 0.05)
				(type default)
			)
			(fill no)
			(layer "F.CrtYd")
		)
		(fp_line
			(start -0.494 0.248)
			(end -0.494 -0.25)
			(stroke
				(width 0.15)
				(type solid)
			)
			(layer "F.Fab")
		)
		(fp_line
			(start 0.504 0.248)
			(end -0.494 0.248)
			(stroke
				(width 0.15)
				(type solid)
			)
			(layer "F.Fab")
		)
		(fp_line
			(start -0.494 -0.25)
			(end 0.504 -0.25)
			(stroke
				(width 0.15)
				(type solid)
			)
			(layer "F.Fab")
		)
		(fp_line
			(start 0.504 -0.25)
			(end 0.504 0.248)
			(stroke
				(width 0.15)
				(type solid)
			)
			(layer "F.Fab")
		)
		(fp_text user "Author: Antmicro"
			(at -0.939 3.399 270)
			(layer "F.Fab")
			(effects
				(font
					(size 0.7 0.7)
					(thickness 0.15)
				)
				(justify left bottom)
			)
		)
		(fp_text user "${REFERENCE}"
			(at -0.939 4.599 270)
			(layer "F.Fab")
			(effects
				(font
					(size 0.7 0.7)
					(thickness 0.15)
				)
				(justify left bottom)
			)
		)
		(fp_text user "License: Apache-2.0"
			(at -0.939 5.799 270)
			(layer "F.Fab")
			(effects
				(font
					(size 0.7 0.7)
					(thickness 0.15)
				)
				(justify left bottom)
			)
		)
		(pad "1" smd roundrect
			(at -0.48 0 270)
			(size 0.59 0.64)
			(layers "F.Cu" "F.Mask" "F.Paste")
			(roundrect_rratio 0.25)
			(net 797 "+1V8")
			(pintype "passive")
		)
		(pad "2" smd roundrect
			(at 0.48 0 270)
			(size 0.59 0.64)
			(layers "F.Cu" "F.Mask" "F.Paste")
			(roundrect_rratio 0.25)
			(net 1 "GND")
			(pintype "passive")
		)
	)
	(footprint "antmicro-footprints:C_0402_1005Metric"
		(layer "F.Cu")
		(at 142.625 144.907851 90)
		(descr "Capacitor SMD 0402")
		(tags "capacitor SMD 0402")
		(property "Reference" "C157"
			(at -5.992149 0.325 90)
			(layer "F.SilkS")
			(effects
				(font
					(size 0.7 0.7)
					(thickness 0.15)
				)
				(justify left bottom)
			)
		)
		(property "Value" "C_100n_0402"
			(at -1.022927 2.155213 90)
			(layer "F.Fab")
			(effects
				(font
					(size 0.7 0.7)
					(thickness 0.15)
				)
				(justify left bottom)
			)
		)
		(property "Datasheet" "https://www.murata.com/products/productdetail?partno=GRM155R61H104KE14%23"
			(at 0 0 90)
			(layer "F.Fab")
			(hide yes)
			(effects
				(font
					(size 1.27 1.27)
					(thickness 0.15)
				)
			)
		)
		(property "MPN" "GRM155R61H104KE14D"
			(at 0 0 90)
			(unlocked yes)
			(layer "F.Fab")
			(hide yes)
			(effects
				(font
					(size 1 1)
					(thickness 0.15)
				)
			)
		)
		(property "Manufacturer" "Murata"
			(at 0 0 90)
			(unlocked yes)
			(layer "F.Fab")
			(hide yes)
			(effects
				(font
					(size 1 1)
					(thickness 0.15)
				)
			)
		)
		(property "License" "Apache-2.0"
			(at 0 0 90)
			(unlocked yes)
			(layer "F.Fab")
			(hide yes)
			(effects
				(font
					(size 1 1)
					(thickness 0.15)
				)
			)
		)
		(property "Author" "Antmicro"
			(at 0 0 90)
			(unlocked yes)
			(layer "F.Fab")
			(hide yes)
			(effects
				(font
					(size 1 1)
					(thickness 0.15)
				)
			)
		)
		(property "Val" "100n"
			(at 0 0 90)
			(unlocked yes)
			(layer "F.Fab")
			(hide yes)
			(effects
				(font
					(size 1 1)
					(thickness 0.15)
				)
			)
		)
		(property "Voltage" "50V"
			(at 0 0 90)
			(unlocked yes)
			(layer "F.Fab")
			(hide yes)
			(effects
				(font
					(size 1 1)
					(thickness 0.15)
				)
			)
		)
		(property "Dielectric" "X5R"
			(at 0 0 90)
			(unlocked yes)
			(layer "F.Fab")
			(hide yes)
			(effects
				(font
					(size 1 1)
					(thickness 0.15)
				)
			)
		)
		(sheetname "/Ethernet/")
		(sheetfile "ethernet.kicad_sch")
		(attr smd)
		(fp_rect
			(start -0.925 -0.47)
			(end 0.925 0.47)
			(stroke
				(width 0.05)
				(type default)
			)
			(fill no)
			(layer "F.CrtYd")
		)
		(fp_line
			(start 0.504 -0.25)
			(end 0.504 0.248)
			(stroke
				(width 0.15)
				(type solid)
			)
			(layer "F.Fab")
		)
		(fp_line
			(start -0.494 -0.25)
			(end 0.504 -0.25)
			(stroke
				(width 0.15)
				(type solid)
			)
			(layer "F.Fab")
		)
		(fp_line
			(start 0.504 0.248)
			(end -0.494 0.248)
			(stroke
				(width 0.15)
				(type solid)
			)
			(layer "F.Fab")
		)
		(fp_line
			(start -0.494 0.248)
			(end -0.494 -0.25)
			(stroke
				(width 0.15)
				(type solid)
			)
			(layer "F.Fab")
		)
		(fp_text user "${REFERENCE}"
			(at -0.939 4.599 90)
			(layer "F.Fab")
			(effects
				(font
					(size 0.7 0.7)
					(thickness 0.15)
				)
				(justify left bottom)
			)
		)
		(fp_text user "License: Apache-2.0"
			(at -0.939 5.799 90)
			(layer "F.Fab")
			(effects
				(font
					(size 0.7 0.7)
					(thickness 0.15)
				)
				(justify left bottom)
			)
		)
		(fp_text user "Author: Antmicro"
			(at -0.939 3.399 90)
			(layer "F.Fab")
			(effects
				(font
					(size 0.7 0.7)
					(thickness 0.15)
				)
				(justify left bottom)
			)
		)
		(pad "1" smd roundrect
			(at -0.48 0 90)
			(size 0.59 0.64)
			(layers "F.Cu" "F.Mask" "F.Paste")
			(roundrect_rratio 0.25)
			(net 1 "GND")
			(pintype "passive")
		)
		(pad "2" smd roundrect
			(at 0.48 0 90)
			(size 0.59 0.64)
			(layers "F.Cu" "F.Mask" "F.Paste")
			(roundrect_rratio 0.25)
			(net 96 "/Ethernet/AVDDL_PLL")
			(pintype "passive")
		)
	)
	(footprint "antmicro-footprints:C_0402_1005Metric"
		(layer "F.Cu")
		(at 129.625 140.182157 90)
		(descr "Capacitor SMD 0402")
		(tags "capacitor SMD 0402")
		(property "Reference" "C149"
			(at -1.042843 -1.65 90)
			(layer "F.SilkS")
			(effects
				(font
					(size 0.7 0.7)
					(thickness 0.15)
				)
				(justify left bottom)
			)
		)
		(property "Value" "C_470n_0402"
			(at -1.022927 2.155213 90)
			(layer "F.Fab")
			(effects
				(font
					(size 0.7 0.7)
					(thickness 0.15)
				)
				(justify left bottom)
			)
		)
		(property "Datasheet" "https://product.tdk.com/en/search/capacitor/ceramic/mlcc/info?part_no=C1005X5R1E474M050BB"
			(at 0 0 90)
			(layer "F.Fab")
			(hide yes)
			(effects
				(font
					(size 1.27 1.27)
					(thickness 0.15)
				)
			)
		)
		(property "Manufacturer" "TDK"
			(at 0 0 90)
			(unlocked yes)
			(layer "F.Fab")
			(hide yes)
			(effects
				(font
					(size 1 1)
					(thickness 0.15)
				)
			)
		)
		(property "MPN" "C1005X5R1E474M050BB"
			(at 0 0 90)
			(unlocked yes)
			(layer "F.Fab")
			(hide yes)
			(effects
				(font
					(size 1 1)
					(thickness 0.15)
				)
			)
		)
		(property "Val" "470n"
			(at 0 0 90)
			(unlocked yes)
			(layer "F.Fab")
			(hide yes)
			(effects
				(font
					(size 1 1)
					(thickness 0.15)
				)
			)
		)
		(property "License" "Apache-2.0"
			(at 0 0 90)
			(unlocked yes)
			(layer "F.Fab")
			(hide yes)
			(effects
				(font
					(size 1 1)
					(thickness 0.15)
				)
			)
		)
		(property "Author" "Antmicro"
			(at 0 0 90)
			(unlocked yes)
			(layer "F.Fab")
			(hide yes)
			(effects
				(font
					(size 1 1)
					(thickness 0.15)
				)
			)
		)
		(property "Voltage" ""
			(at 0 0 90)
			(unlocked yes)
			(layer "F.Fab")
			(hide yes)
			(effects
				(font
					(size 1 1)
					(thickness 0.15)
				)
			)
		)
		(property "Dielectric" ""
			(at 0 0 90)
			(unlocked yes)
			(layer "F.Fab")
			(hide yes)
			(effects
				(font
					(size 1 1)
					(thickness 0.15)
				)
			)
		)
		(sheetname "/Ethernet/")
		(sheetfile "ethernet.kicad_sch")
		(attr smd)
		(fp_rect
			(start -0.925 -0.47)
			(end 0.925 0.47)
			(stroke
				(width 0.05)
				(type default)
			)
			(fill no)
			(layer "F.CrtYd")
		)
		(fp_line
			(start 0.504 -0.25)
			(end 0.504 0.248)
			(stroke
				(width 0.15)
				(type solid)
			)
			(layer "F.Fab")
		)
		(fp_line
			(start -0.494 -0.25)
			(end 0.504 -0.25)
			(stroke
				(width 0.15)
				(type solid)
			)
			(layer "F.Fab")
		)
		(fp_line
			(start 0.504 0.248)
			(end -0.494 0.248)
			(stroke
				(width 0.15)
				(type solid)
			)
			(layer "F.Fab")
		)
		(fp_line
			(start -0.494 0.248)
			(end -0.494 -0.25)
			(stroke
				(width 0.15)
				(type solid)
			)
			(layer "F.Fab")
		)
		(fp_text user "${REFERENCE}"
			(at -0.939 4.599 90)
			(layer "F.Fab")
			(effects
				(font
					(size 0.7 0.7)
					(thickness 0.15)
				)
				(justify left bottom)
			)
		)
		(fp_text user "Author: Antmicro"
			(at -0.939 3.399 90)
			(layer "F.Fab")
			(effects
				(font
					(size 0.7 0.7)
					(thickness 0.15)
				)
				(justify left bottom)
			)
		)
		(fp_text user "License: Apache-2.0"
			(at -0.939 5.799 90)
			(layer "F.Fab")
			(effects
				(font
					(size 0.7 0.7)
					(thickness 0.15)
				)
				(justify left bottom)
			)
		)
		(pad "1" smd roundrect
			(at -0.48 0 90)
			(size 0.59 0.64)
			(layers "F.Cu" "F.Mask" "F.Paste")
			(roundrect_rratio 0.25)
			(net 150 "+1V2")
			(pintype "passive")
		)
		(pad "2" smd roundrect
			(at 0.48 0 90)
			(size 0.59 0.64)
			(layers "F.Cu" "F.Mask" "F.Paste")
			(roundrect_rratio 0.25)
			(net 1 "GND")
			(pintype "passive")
		)
	)
	(footprint "antmicro-footprints:C_0402_1005Metric"
		(layer "F.Cu")
		(at 143.725 144.907851 90)
		(descr "Capacitor SMD 0402")
		(tags "capacitor SMD 0402")
		(property "Reference" "C154"
			(at -5.992149 0.2 90)
			(layer "F.SilkS")
			(effects
				(font
					(size 0.7 0.7)
					(thickness 0.15)
				)
				(justify left bottom)
			)
		)
		(property "Value" "C_10n_0402"
			(at -1.022927 2.155213 90)
			(layer "F.Fab")
			(effects
				(font
					(size 0.7 0.7)
					(thickness 0.15)
				)
				(justify left bottom)
			)
		)
		(property "Datasheet" "https://www.murata.com/products/productdetail?partno=GRM155R71H103KA88%23"
			(at 0 0 90)
			(layer "F.Fab")
			(hide yes)
			(effects
				(font
					(size 1.27 1.27)
					(thickness 0.15)
				)
			)
		)
		(property "Manufacturer" "Murata"
			(at 0 0 90)
			(unlocked yes)
			(layer "F.Fab")
			(hide yes)
			(effects
				(font
					(size 1 1)
					(thickness 0.15)
				)
			)
		)
		(property "MPN" "GRM155R71H103KA88D"
			(at 0 0 90)
			(unlocked yes)
			(layer "F.Fab")
			(hide yes)
			(effects
				(font
					(size 1 1)
					(thickness 0.15)
				)
			)
		)
		(property "Val" "10n"
			(at 0 0 90)
			(unlocked yes)
			(layer "F.Fab")
			(hide yes)
			(effects
				(font
					(size 1 1)
					(thickness 0.15)
				)
			)
		)
		(property "License" "Apache-2.0"
			(at 0 0 90)
			(unlocked yes)
			(layer "F.Fab")
			(hide yes)
			(effects
				(font
					(size 1 1)
					(thickness 0.15)
				)
			)
		)
		(property "Author" "Antmicro"
			(at 0 0 90)
			(unlocked yes)
			(layer "F.Fab")
			(hide yes)
			(effects
				(font
					(size 1 1)
					(thickness 0.15)
				)
			)
		)
		(property "Voltage" "50V"
			(at 0 0 90)
			(unlocked yes)
			(layer "F.Fab")
			(hide yes)
			(effects
				(font
					(size 1 1)
					(thickness 0.15)
				)
			)
		)
		(property "Dielectric" "X7R"
			(at 0 0 90)
			(unlocked yes)
			(layer "F.Fab")
			(hide yes)
			(effects
				(font
					(size 1 1)
					(thickness 0.15)
				)
			)
		)
		(sheetname "/Ethernet/")
		(sheetfile "ethernet.kicad_sch")
		(attr smd)
		(fp_rect
			(start -0.925 -0.47)
			(end 0.925 0.47)
			(stroke
				(width 0.05)
				(type default)
			)
			(fill no)
			(layer "F.CrtYd")
		)
		(fp_line
			(start 0.504 -0.25)
			(end 0.504 0.248)
			(stroke
				(width 0.15)
				(type solid)
			)
			(layer "F.Fab")
		)
		(fp_line
			(start -0.494 -0.25)
			(end 0.504 -0.25)
			(stroke
				(width 0.15)
				(type solid)
			)
			(layer "F.Fab")
		)
		(fp_line
			(start 0.504 0.248)
			(end -0.494 0.248)
			(stroke
				(width 0.15)
				(type solid)
			)
			(layer "F.Fab")
		)
		(fp_line
			(start -0.494 0.248)
			(end -0.494 -0.25)
			(stroke
				(width 0.15)
				(type solid)
			)
			(layer "F.Fab")
		)
		(fp_text user "License: Apache-2.0"
			(at -0.939 5.799 90)
			(layer "F.Fab")
			(effects
				(font
					(size 0.7 0.7)
					(thickness 0.15)
				)
				(justify left bottom)
			)
		)
		(fp_text user "${REFERENCE}"
			(at -0.939 4.599 90)
			(layer "F.Fab")
			(effects
				(font
					(size 0.7 0.7)
					(thickness 0.15)
				)
				(justify left bottom)
			)
		)
		(fp_text user "Author: Antmicro"
			(at -0.939 3.399 90)
			(layer "F.Fab")
			(effects
				(font
					(size 0.7 0.7)
					(thickness 0.15)
				)
				(justify left bottom)
			)
		)
		(pad "1" smd roundrect
			(at -0.48 0 90)
			(size 0.59 0.64)
			(layers "F.Cu" "F.Mask" "F.Paste")
			(roundrect_rratio 0.25)
			(net 1 "GND")
			(pintype "passive")
		)
		(pad "2" smd roundrect
			(at 0.48 0 90)
			(size 0.59 0.64)
			(layers "F.Cu" "F.Mask" "F.Paste")
			(roundrect_rratio 0.25)
			(net 96 "/Ethernet/AVDDL_PLL")
			(pintype "passive")
		)
	)
)
